# TIMECARD (Time Appliance Project (Time Card)) — schematic netlist excerpt (pin names and nets, part order shuffled) for the footprints in the layout excerpt that follows; sources: Cadence DE-HDL packaged netlist, KiCad conversion of R4006-B0001-02_R01.brd

C52  CAPACITOR  0.1UF 25V 10%  pkg SMC_0402R_H022  page 28 : \1\ = VIN_XP3R3 ; \2\ = SG
C50  CAPACITOR  10UF 25V 20%  pkg SMC_0805R_H057  page 28 : \1\ = VIN_XP3R3 ; \2\ = SG

(kicad_pcb
	(version 20260206)
	(generator "pcbnew")
	(generator_version "10.0")
	(general
		(thickness 1.6)
		(legacy_teardrops no)
	)
	(paper "A4")
	(title_block
		(title "timecard-production-celestica-r4006 — R4006-B0001-02_R01.brd")
		(comment 1 "Time Appliance Project (Time Card) / footprints 293-294 of 1113")
	)
	(layers
		(0 "F.Cu" signal "TOP")
		(4 "In1.Cu" signal "L02_GND1")
		(6 "In2.Cu" signal "L03_SIG1")
		(8 "In3.Cu" signal "L04_GND2")
		(10 "In4.Cu" signal "L05_VCC1")
		(12 "In5.Cu" signal "L06_VCC2")
		(14 "In6.Cu" signal "L07_GND3")
		(16 "In7.Cu" signal "L08_SIG2")
		(18 "In8.Cu" signal "L09_GND4")
		(2 "B.Cu" signal "BOTTOM")
		(9 "F.Adhes" user "F.Adhesive")
		(11 "B.Adhes" user "B.Adhesive")
		(13 "F.Paste" user "Package Geometry/Pastemask Top")
		(15 "B.Paste" user "Package Geometry/Pastemask Bottom")
		(5 "F.SilkS" user "Ref Des/Silkscreen Top")
		(7 "B.SilkS" user "Ref Des/Silkscreen Bottom")
		(1 "F.Mask" user "Board Geometry/Soldermask Top")
		(3 "B.Mask" user "Board Geometry/Soldermask Bottom")
		(17 "Dwgs.User" user "User.Drawings")
		(19 "Cmts.User" user "User.Comments")
		(21 "Eco1.User" user "User.Eco1")
		(23 "Eco2.User" user "User.Eco2")
		(25 "Edge.Cuts" user "Board Geometry/Outline")
		(27 "Margin" user)
		(31 "F.CrtYd" user "Package Geometry/Place Bound Top")
		(29 "B.CrtYd" user "Package Geometry/Place Bound Bottom")
		(35 "F.Fab" user "Ref Des/Assembly Top")
		(33 "B.Fab" user "Ref Des/Assembly Bottom")
	)
	(footprint ""
		(layer "F.Cu")
		(at 83.5152 -106.7308 180)
		(property "Reference" "C50"
			(at -0.3048 1.68783 0)
			(unlocked yes)
			(layer "F.SilkS")
			(effects
				(font
					(size 0.7874 0.5842)
					(thickness 0.1524)
				)
			)
		)
		(property "Value" "VAL*"
			(at 0.0762 3.134106 180)
			(unlocked yes)
			(layer "F.Fab")
			(hide yes)
			(effects
				(font
					(size 0.7874 0.5842)
					(thickness 0.1524)
				)
			)
		)
		(property "Tolerance" "TOL*"
			(at 0.0762 4.048506 180)
			(unlocked yes)
			(layer "Cmts.User")
			(hide yes)
			(effects
				(font
					(size 0.7874 0.5842)
					(thickness 0.1524)
				)
			)
		)
		(property "User Part Number" "PARTNUM*"
			(at 0.1016 5.013706 180)
			(unlocked yes)
			(layer "Cmts.User")
			(hide yes)
			(effects
				(font
					(size 0.7874 0.5842)
					(thickness 0.1524)
				)
			)
		)
		(property "Device Type" "CAPACITOR-G107-0F106-EM,10UF,2A"
			(at 0.0508 2.194306 180)
			(unlocked yes)
			(layer "F.Fab")
			(hide yes)
			(effects
				(font
					(size 0.7874 0.5842)
					(thickness 0.1524)
				)
			)
		)
		(duplicate_pad_numbers_are_jumpers no)
		(fp_line
			(start 1.5748 0.9398)
			(end 1.5748 -0.9398)
			(stroke
				(width 0.1)
				(type default)
			)
			(layer "F.SilkS")
		)
		(fp_line
			(start 1.5748 -0.9398)
			(end -1.5748 -0.9398)
			(stroke
				(width 0.1)
				(type default)
			)
			(layer "F.SilkS")
		)
		(fp_line
			(start -1.5748 0.9398)
			(end 1.5748 0.9398)
			(stroke
				(width 0.1)
				(type default)
			)
			(layer "F.SilkS")
		)
		(fp_line
			(start -1.5748 -0.9398)
			(end -1.5748 0.9398)
			(stroke
				(width 0.1)
				(type default)
			)
			(layer "F.SilkS")
		)
		(fp_rect
			(start 1.5748 -0.9398)
			(end -1.5748 0.9398)
			(stroke
				(width 0)
				(type default)
			)
			(fill no)
			(layer "F.CrtYd")
		)
		(fp_line
			(start 1.016 0.635)
			(end 1.016 -0.635)
			(stroke
				(width 0.1)
				(type default)
			)
			(layer "F.Fab")
		)
		(fp_line
			(start 1.016 -0.635)
			(end -1.016 -0.635)
			(stroke
				(width 0.1)
				(type default)
			)
			(layer "F.Fab")
		)
		(fp_line
			(start -1.016 0.635)
			(end 1.016 0.635)
			(stroke
				(width 0.1)
				(type default)
			)
			(layer "F.Fab")
		)
		(fp_line
			(start -1.016 -0.635)
			(end -1.016 0.635)
			(stroke
				(width 0.1)
				(type default)
			)
			(layer "F.Fab")
		)
		(pad "1" smd rect
			(at -0.8382 0 180)
			(size 0.9652 1.3716)
			(layers "F.Cu" "F.Mask" "F.Paste")
			(net "VIN_XP3R3")
		)
		(pad "2" smd rect
			(at 0.8382 0 180)
			(size 0.9652 1.3716)
			(layers "F.Cu" "F.Mask" "F.Paste")
			(net "SG")
		)
		(zone
			(layer "F.Cu")
			(hatch none 0.5)
			(connect_pads
				(clearance 0)
			)
			(min_thickness 0.25)
			(keepout
				(tracks allowed)
				(vias not_allowed)
				(pads allowed)
				(copperpour not_allowed)
				(footprints allowed)
			)
			(placement
				(enabled no)
				(sheetname "")
			)
			(fill
				(thermal_gap 0.5)
				(thermal_bridge_width 0.5)
				(island_removal_mode 0)
			)
			(polygon
				(pts
					(xy 83.2866 -106.0958) (xy 83.7438 -106.0958) (xy 83.7438 -107.3658) (xy 83.2866 -107.3658)
				)
			)
		)
	)
	(footprint ""
		(layer "F.Cu")
		(at 84.5312 -98.7298 180)
		(property "Reference" "C52"
			(at 4.6482 -6.18617 0)
			(unlocked yes)
			(layer "F.SilkS")
			(effects
				(font
					(size 0.7874 0.5842)
					(thickness 0.1524)
				)
			)
		)
		(property "Value" "VAL*"
			(at 0.0762 2.067306 180)
			(unlocked yes)
			(layer "F.Fab")
			(hide yes)
			(effects
				(font
					(size 0.7874 0.5842)
					(thickness 0.1524)
				)
			)
		)
		(property "Tolerance" "TOL*"
			(at 0.0762 3.032506 180)
			(unlocked yes)
			(layer "Cmts.User")
			(hide yes)
			(effects
				(font
					(size 0.7874 0.5842)
					(thickness 0.1524)
				)
			)
		)
		(property "User Part Number" "PARTNUM*"
			(at 0.1016 4.023106 180)
			(unlocked yes)
			(layer "Cmts.User")
			(hide yes)
			(effects
				(font
					(size 0.7874 0.5842)
					(thickness 0.1524)
				)
			)
		)
		(property "Device Type" "CAPACITOR-G105-0B104-EK,0.1UF,A"
			(at 0.0508 1.127506 180)
			(unlocked yes)
			(layer "F.Fab")
			(hide yes)
			(effects
				(font
					(size 0.7874 0.5842)
					(thickness 0.1524)
				)
			)
		)
		(duplicate_pad_numbers_are_jumpers no)
		(fp_line
			(start 1.143 0.5588)
			(end 1.143 -0.5588)
			(stroke
				(width 0.1)
				(type default)
			)
			(layer "F.SilkS")
		)
		(fp_line
			(start 1.143 -0.5588)
			(end -1.143 -0.5588)
			(stroke
				(width 0.1)
				(type default)
			)
			(layer "F.SilkS")
		)
		(fp_line
			(start -1.143 0.5588)
			(end 1.143 0.5588)
			(stroke
				(width 0.1)
				(type default)
			)
			(layer "F.SilkS")
		)
		(fp_line
			(start -1.143 -0.5588)
			(end -1.143 0.5588)
			(stroke
				(width 0.1)
				(type default)
			)
			(layer "F.SilkS")
		)
		(fp_rect
			(start 1.143 -0.5588)
			(end -1.143 0.5588)
			(stroke
				(width 0)
				(type default)
			)
			(fill no)
			(layer "F.CrtYd")
		)
		(fp_line
			(start 0.508 0.3048)
			(end 0.508 -0.3048)
			(stroke
				(width 0.1)
				(type default)
			)
			(layer "F.Fab")
		)
		(fp_line
			(start 0.508 -0.3048)
			(end -0.508 -0.3048)
			(stroke
				(width 0.1)
				(type default)
			)
			(layer "F.Fab")
		)
		(fp_line
			(start -0.508 0.3048)
			(end 0.508 0.3048)
			(stroke
				(width 0.1)
				(type default)
			)
			(layer "F.Fab")
		)
		(fp_line
			(start -0.508 -0.3048)
			(end -0.508 0.3048)
			(stroke
				(width 0.1)
				(type default)
			)
			(layer "F.Fab")
		)
		(pad "1" smd rect
			(at -0.5334 0 180)
			(size 0.7112 0.6096)
			(layers "F.Cu" "F.Mask" "F.Paste")
			(net "VIN_XP3R3")
		)
		(pad "2" smd rect
			(at 0.5334 0 180)
			(size 0.7112 0.6096)
			(layers "F.Cu" "F.Mask" "F.Paste")
			(net "SG")
		)
		(zone
			(layer "F.Cu")
			(hatch none 0.5)
			(connect_pads
				(clearance 0)
			)
			(min_thickness 0.25)
			(keepout
				(tracks allowed)
				(vias not_allowed)
				(pads allowed)
				(copperpour not_allowed)
				(footprints allowed)
			)
			(placement
				(enabled no)
				(sheetname "")
			)
			(fill
				(thermal_gap 0.5)
				(thermal_bridge_width 0.5)
				(island_removal_mode 0)
			)
			(polygon
				(pts
					(xy 84.455 -98.425) (xy 84.6074 -98.425) (xy 84.6074 -99.0346) (xy 84.455 -99.0346)
				)
			)
		)
	)
)
